(kicad_pcb
	(version 20260206)
	(generator "pcbnew")
	(generator_version "10.0")
	(general
		(thickness 1.6)
		(legacy_teardrops no)
	)
	(paper "A4")
	(title_block
		(title "01162023_DA0F0TEBIF0_F0T_Expander_BD_F_brd_V02_OCP.brd")
		(comment 1 "Grand Teton / footprints 8552-8560 of 9728")
	)
	(layers
		(0 "F.Cu" signal "TOP")
		(4 "In1.Cu" signal "GND")
		(6 "In2.Cu" signal "VCC")
		(8 "In3.Cu" signal "VCC1")
		(10 "In4.Cu" signal "GND1")
		(12 "In5.Cu" signal "IN1")
		(14 "In6.Cu" signal "GND2")
		(16 "In7.Cu" signal "IN2")
		(18 "In8.Cu" signal "GND3")
		(20 "In9.Cu" signal "IN3")
		(22 "In10.Cu" signal "GND4")
		(24 "In11.Cu" signal "IN4")
		(26 "In12.Cu" signal "GND5")
		(28 "In13.Cu" signal "IN5")
		(30 "In14.Cu" signal "GND6")
		(32 "In15.Cu" signal "IN6")
		(34 "In16.Cu" signal "GND7")
		(2 "B.Cu" signal "BOTTOM")
		(9 "F.Adhes" user "F.Adhesive")
		(11 "B.Adhes" user "B.Adhesive")
		(13 "F.Paste" user "Package Geometry/Pastemask Top")
		(15 "B.Paste" user "Package Geometry/Pastemask Bottom")
		(5 "F.SilkS" user "Ref Des/Silkscreen Top")
		(7 "B.SilkS" user "Ref Des/Silkscreen Bottom")
		(1 "F.Mask" user "Board Geometry/Soldermask Top")
		(3 "B.Mask" user "Board Geometry/Soldermask Bottom")
		(17 "Dwgs.User" user "User.Drawings")
		(19 "Cmts.User" user "User.Comments")
		(21 "Eco1.User" user "User.Eco1")
		(23 "Eco2.User" user "User.Eco2")
		(25 "Edge.Cuts" user "Board Geometry/Outline")
		(27 "Margin" user)
		(31 "F.CrtYd" user "Package Geometry/Place Bound Top")
		(29 "B.CrtYd" user "Package Geometry/Place Bound Bottom")
		(35 "F.Fab" user "Ref Des/Assembly Top")
		(33 "B.Fab" user "Ref Des/Assembly Bottom")
	)
	(footprint ""
		(layer "B.Cu")
		(at 417.241482 -287.824926)
		(property "Reference" "C3519"
			(at 0 0 0)
			(layer "B.SilkS")
			(hide yes)
			(effects
				(font
					(size 1.27 1.27)
				)
				(justify mirror)
			)
		)
		(property "Value" ""
			(at 0 0 0)
			(layer "B.Fab")
			(effects
				(font
					(size 1.27 1.27)
				)
				(justify mirror)
			)
		)
		(duplicate_pad_numbers_are_jumpers no)
		(fp_line
			(start -0.299974 -0.150114)
			(end -0.299974 0.150114)
			(stroke
				(width 0.1)
				(type default)
			)
			(layer "B.Fab")
		)
		(fp_line
			(start -0.299974 0.150114)
			(end 0.299974 0.150114)
			(stroke
				(width 0.1)
				(type default)
			)
			(layer "B.Fab")
		)
		(fp_line
			(start 0.299974 -0.150114)
			(end -0.299974 -0.150114)
			(stroke
				(width 0.1)
				(type default)
			)
			(layer "B.Fab")
		)
		(fp_line
			(start 0.299974 0.150114)
			(end 0.299974 -0.150114)
			(stroke
				(width 0.1)
				(type default)
			)
			(layer "B.Fab")
		)
		(pad "1" smd rect
			(at 0.2667 0 180)
			(size 0.3048 0.381)
			(layers "B.Cu" "B.Mask" "B.Paste")
			(net "P1V8_VDDA_PEX3")
		)
		(pad "2" smd rect
			(at -0.2667 0 180)
			(size 0.3048 0.381)
			(layers "B.Cu" "B.Mask" "B.Paste")
			(net "GND")
		)
	)
	(footprint ""
		(layer "B.Cu")
		(at 178.280314 -295.221914)
		(property "Reference" "C1357"
			(at 0 0 0)
			(layer "B.SilkS")
			(hide yes)
			(effects
				(font
					(size 1.27 1.27)
				)
				(justify mirror)
			)
		)
		(property "Value" ""
			(at 0 0 0)
			(layer "B.Fab")
			(effects
				(font
					(size 1.27 1.27)
				)
				(justify mirror)
			)
		)
		(duplicate_pad_numbers_are_jumpers no)
		(fp_line
			(start -1.2954 -0.5842)
			(end -1.2954 0.5842)
			(stroke
				(width 0.1524)
				(type default)
			)
			(layer "B.SilkS")
		)
		(fp_line
			(start -1.2954 0.5842)
			(end 1.2954 0.5842)
			(stroke
				(width 0.1524)
				(type default)
			)
			(layer "B.SilkS")
		)
		(fp_line
			(start 1.2954 -0.5842)
			(end -1.2954 -0.5842)
			(stroke
				(width 0.1524)
				(type default)
			)
			(layer "B.SilkS")
		)
		(fp_line
			(start 1.2954 0.5842)
			(end 1.2954 -0.5842)
			(stroke
				(width 0.1524)
				(type default)
			)
			(layer "B.SilkS")
		)
		(fp_line
			(start -1.1938 -0.4064)
			(end -1.1938 0.4064)
			(stroke
				(width 0.1)
				(type default)
			)
			(layer "B.Fab")
		)
		(fp_line
			(start -1.1938 0.4064)
			(end -0.8636 0.4064)
			(stroke
				(width 0.1)
				(type default)
			)
			(layer "B.Fab")
		)
		(fp_line
			(start -0.8636 -0.4572)
			(end -0.8636 -0.4064)
			(stroke
				(width 0.1)
				(type default)
			)
			(layer "B.Fab")
		)
		(fp_line
			(start -0.8636 -0.4064)
			(end -1.1938 -0.4064)
			(stroke
				(width 0.1)
				(type default)
			)
			(layer "B.Fab")
		)
		(fp_line
			(start -0.8636 0.4064)
			(end -0.8636 0.4572)
			(stroke
				(width 0.1)
				(type default)
			)
			(layer "B.Fab")
		)
		(fp_line
			(start -0.8636 0.4572)
			(end 0.8636 0.4572)
			(stroke
				(width 0.1)
				(type default)
			)
			(layer "B.Fab")
		)
		(fp_line
			(start 0.8636 -0.4572)
			(end -0.8636 -0.4572)
			(stroke
				(width 0.1)
				(type default)
			)
			(layer "B.Fab")
		)
		(fp_line
			(start 0.8636 -0.4064)
			(end 0.8636 -0.4572)
			(stroke
				(width 0.1)
				(type default)
			)
			(layer "B.Fab")
		)
		(fp_line
			(start 0.8636 0.4064)
			(end 1.1938 0.4064)
			(stroke
				(width 0.1)
				(type default)
			)
			(layer "B.Fab")
		)
		(fp_line
			(start 0.8636 0.4572)
			(end 0.8636 0.4064)
			(stroke
				(width 0.1)
				(type default)
			)
			(layer "B.Fab")
		)
		(fp_line
			(start 1.1938 -0.4064)
			(end 0.8636 -0.4064)
			(stroke
				(width 0.1)
				(type default)
			)
			(layer "B.Fab")
		)
		(fp_line
			(start 1.1938 0.4064)
			(end 1.1938 -0.4064)
			(stroke
				(width 0.1)
				(type default)
			)
			(layer "B.Fab")
		)
		(pad "1" smd rect
			(at 0.7366 0 270)
			(size 0.7112 0.8128)
			(layers "B.Cu" "B.Mask" "B.Paste")
			(net "P0V8_PEX1")
		)
		(pad "2" smd rect
			(at -0.7366 0 270)
			(size 0.7112 0.8128)
			(layers "B.Cu" "B.Mask" "B.Paste")
			(net "GND")
		)
	)
	(footprint ""
		(layer "B.Cu")
		(at 346.893896 -226.787202 -90)
		(property "Reference" "C2038"
			(at 0 0 90)
			(layer "B.SilkS")
			(hide yes)
			(effects
				(font
					(size 1.27 1.27)
				)
				(justify mirror)
			)
		)
		(property "Value" ""
			(at 0 0 90)
			(layer "B.Fab")
			(effects
				(font
					(size 1.27 1.27)
				)
				(justify mirror)
			)
		)
		(duplicate_pad_numbers_are_jumpers no)
		(fp_line
			(start -0.69215 0.2921)
			(end 0.69215 0.2921)
			(stroke
				(width 0.1524)
				(type default)
			)
			(layer "B.SilkS")
		)
		(fp_line
			(start 0.69215 0.2921)
			(end 0.69215 -0.2921)
			(stroke
				(width 0.1524)
				(type default)
			)
			(layer "B.SilkS")
		)
		(fp_line
			(start -0.69215 -0.2921)
			(end -0.69215 0.2921)
			(stroke
				(width 0.1524)
				(type default)
			)
			(layer "B.SilkS")
		)
		(fp_line
			(start 0.69215 -0.2921)
			(end -0.69215 -0.2921)
			(stroke
				(width 0.1524)
				(type default)
			)
			(layer "B.SilkS")
		)
		(fp_line
			(start -0.51435 0.2794)
			(end 0.51435 0.2794)
			(stroke
				(width 0.1)
				(type default)
			)
			(layer "B.Fab")
		)
		(fp_line
			(start 0.51435 0.2794)
			(end 0.51435 -0.2794)
			(stroke
				(width 0.1)
				(type default)
			)
			(layer "B.Fab")
		)
		(fp_line
			(start -0.51435 -0.2794)
			(end -0.51435 0.2794)
			(stroke
				(width 0.1)
				(type default)
			)
			(layer "B.Fab")
		)
		(fp_line
			(start 0.51435 -0.2794)
			(end -0.51435 -0.2794)
			(stroke
				(width 0.1)
				(type default)
			)
			(layer "B.Fab")
		)
		(pad "1" smd circle
			(at 0.40005 0 90)
			(size 0 0)
			(layers "B.Cu" "B.Mask" "B.Paste")
			(net "P3V3_FPGA_VCCIO0")
		)
		(pad "2" smd circle
			(at -0.40005 0 90)
			(size 0 0)
			(layers "B.Cu" "B.Mask" "B.Paste")
			(net "GND")
		)
		(zone
			(layer "B.Cu")
			(hatch none 0.5)
			(connect_pads
				(clearance 0)
			)
			(min_thickness 0.25)
			(keepout
				(tracks not_allowed)
				(vias allowed)
				(pads allowed)
				(copperpour not_allowed)
				(footprints allowed)
			)
			(placement
				(enabled no)
				(sheetname "")
			)
			(fill
				(thermal_gap 0.5)
				(thermal_bridge_width 0.5)
				(island_removal_mode 0)
			)
			(polygon
				(pts
					(xy 346.806266 -226.596702) (xy 346.7481 -226.688142) (xy 346.7481 -226.887532) (xy 346.806266 -226.977702)
					(xy 346.981526 -226.977702) (xy 347.039946 -226.887532) (xy 347.039946 -226.688142) (xy 346.98178 -226.596702)
				)
			)
		)
	)
	(footprint ""
		(layer "B.Cu")
		(at 397.49984 -292.574726 180)
		(property "Reference" "C1869"
			(at 0 0 0)
			(layer "B.SilkS")
			(hide yes)
			(effects
				(font
					(size 1.27 1.27)
				)
				(justify mirror)
			)
		)
		(property "Value" ""
			(at 0 0 0)
			(layer "B.Fab")
			(effects
				(font
					(size 1.27 1.27)
				)
				(justify mirror)
			)
		)
		(duplicate_pad_numbers_are_jumpers no)
		(fp_line
			(start 0.299974 0.150114)
			(end 0.299974 -0.150114)
			(stroke
				(width 0.1)
				(type default)
			)
			(layer "B.Fab")
		)
		(fp_line
			(start 0.299974 -0.150114)
			(end -0.299974 -0.150114)
			(stroke
				(width 0.1)
				(type default)
			)
			(layer "B.Fab")
		)
		(fp_line
			(start -0.299974 0.150114)
			(end 0.299974 0.150114)
			(stroke
				(width 0.1)
				(type default)
			)
			(layer "B.Fab")
		)
		(fp_line
			(start -0.299974 -0.150114)
			(end -0.299974 0.150114)
			(stroke
				(width 0.1)
				(type default)
			)
			(layer "B.Fab")
		)
		(pad "1" smd rect
			(at 0.2667 0)
			(size 0.3048 0.381)
			(layers "B.Cu" "B.Mask" "B.Paste")
			(net "P0V8_PEX3")
		)
		(pad "2" smd rect
			(at -0.2667 0)
			(size 0.3048 0.381)
			(layers "B.Cu" "B.Mask" "B.Paste")
			(net "GND")
		)
	)
	(footprint ""
		(layer "B.Cu")
		(at 213.935056 -214.24646 180)
		(property "Reference" "R5530"
			(at 0 0 0)
			(layer "B.SilkS")
			(hide yes)
			(effects
				(font
					(size 1.27 1.27)
				)
				(justify mirror)
			)
		)
		(property "Value" ""
			(at 0 0 0)
			(layer "B.Fab")
			(effects
				(font
					(size 1.27 1.27)
				)
				(justify mirror)
			)
		)
		(duplicate_pad_numbers_are_jumpers no)
		(fp_line
			(start 0.7874 0.4064)
			(end 0.7874 -0.4064)
			(stroke
				(width 0.1524)
				(type default)
			)
			(layer "B.SilkS")
		)
		(fp_line
			(start 0.7874 -0.4064)
			(end -0.7874 -0.4064)
			(stroke
				(width 0.1524)
				(type default)
			)
			(layer "B.SilkS")
		)
		(fp_line
			(start -0.7874 0.4064)
			(end 0.7874 0.4064)
			(stroke
				(width 0.1524)
				(type default)
			)
			(layer "B.SilkS")
		)
		(fp_line
			(start -0.7874 -0.4064)
			(end -0.7874 0.4064)
			(stroke
				(width 0.1524)
				(type default)
			)
			(layer "B.SilkS")
		)
		(fp_line
			(start 0.67945 0.3048)
			(end 0.67945 -0.305054)
			(stroke
				(width 0.1)
				(type default)
			)
			(layer "B.Fab")
		)
		(fp_line
			(start 0.67945 -0.305054)
			(end 0.12065 -0.305054)
			(stroke
				(width 0.1)
				(type default)
			)
			(layer "B.Fab")
		)
		(fp_line
			(start 0.12065 0.3048)
			(end 0.67945 0.3048)
			(stroke
				(width 0.1)
				(type default)
			)
			(layer "B.Fab")
		)
		(fp_line
			(start 0.12065 0.2794)
			(end 0.12065 0.3048)
			(stroke
				(width 0.1)
				(type default)
			)
			(layer "B.Fab")
		)
		(fp_line
			(start 0.12065 -0.2794)
			(end -0.12065 -0.2794)
			(stroke
				(width 0.1)
				(type default)
			)
			(layer "B.Fab")
		)
		(fp_line
			(start 0.12065 -0.305054)
			(end 0.12065 -0.2794)
			(stroke
				(width 0.1)
				(type default)
			)
			(layer "B.Fab")
		)
		(fp_line
			(start -0.120396 0.3048)
			(end -0.120396 0.2794)
			(stroke
				(width 0.1)
				(type default)
			)
			(layer "B.Fab")
		)
		(fp_line
			(start -0.120396 0.2794)
			(end 0.12065 0.2794)
			(stroke
				(width 0.1)
				(type default)
			)
			(layer "B.Fab")
		)
		(fp_line
			(start -0.12065 -0.2794)
			(end -0.12065 -0.3048)
			(stroke
				(width 0.1)
				(type default)
			)
			(layer "B.Fab")
		)
		(fp_line
			(start -0.12065 -0.3048)
			(end -0.67945 -0.3048)
			(stroke
				(width 0.1)
				(type default)
			)
			(layer "B.Fab")
		)
		(fp_line
			(start -0.67945 0.3048)
			(end -0.120396 0.3048)
			(stroke
				(width 0.1)
				(type default)
			)
			(layer "B.Fab")
		)
		(fp_line
			(start -0.67945 -0.3048)
			(end -0.67945 0.3048)
			(stroke
				(width 0.1)
				(type default)
			)
			(layer "B.Fab")
		)
		(pad "1" smd circle
			(at 0.40005 0)
			(size 0 0)
			(layers "B.Cu" "B.Mask" "B.Paste")
			(net "P3V3_AUX")
		)
		(pad "2" smd circle
			(at -0.40005 0)
			(size 0 0)
			(layers "B.Cu" "B.Mask" "B.Paste")
			(net "RST_BIC_USB_HUB_R_N")
		)
	)
	(footprint ""
		(layer "B.Cu")
		(at 234.98683 -351.349056 180)
		(property "Reference" "PR7154"
			(at 0 0 0)
			(layer "B.SilkS")
			(hide yes)
			(effects
				(font
					(size 1.27 1.27)
				)
				(justify mirror)
			)
		)
		(property "Value" ""
			(at 0 0 0)
			(layer "B.Fab")
			(effects
				(font
					(size 1.27 1.27)
				)
				(justify mirror)
			)
		)
		(duplicate_pad_numbers_are_jumpers no)
		(fp_line
			(start 0.7874 0.4064)
			(end 0.7874 -0.4064)
			(stroke
				(width 0.1524)
				(type default)
			)
			(layer "B.SilkS")
		)
		(fp_line
			(start 0.7874 -0.4064)
			(end -0.7874 -0.4064)
			(stroke
				(width 0.1524)
				(type default)
			)
			(layer "B.SilkS")
		)
		(fp_line
			(start -0.7874 0.4064)
			(end 0.7874 0.4064)
			(stroke
				(width 0.1524)
				(type default)
			)
			(layer "B.SilkS")
		)
		(fp_line
			(start -0.7874 -0.4064)
			(end -0.7874 0.4064)
			(stroke
				(width 0.1524)
				(type default)
			)
			(layer "B.SilkS")
		)
		(fp_line
			(start 0.67945 0.3048)
			(end 0.67945 -0.305054)
			(stroke
				(width 0.1)
				(type default)
			)
			(layer "B.Fab")
		)
		(fp_line
			(start 0.67945 -0.305054)
			(end 0.12065 -0.305054)
			(stroke
				(width 0.1)
				(type default)
			)
			(layer "B.Fab")
		)
		(fp_line
			(start 0.12065 0.3048)
			(end 0.67945 0.3048)
			(stroke
				(width 0.1)
				(type default)
			)
			(layer "B.Fab")
		)
		(fp_line
			(start 0.12065 0.2794)
			(end 0.12065 0.3048)
			(stroke
				(width 0.1)
				(type default)
			)
			(layer "B.Fab")
		)
		(fp_line
			(start 0.12065 -0.2794)
			(end -0.12065 -0.2794)
			(stroke
				(width 0.1)
				(type default)
			)
			(layer "B.Fab")
		)
		(fp_line
			(start 0.12065 -0.305054)
			(end 0.12065 -0.2794)
			(stroke
				(width 0.1)
				(type default)
			)
			(layer "B.Fab")
		)
		(fp_line
			(start -0.120396 0.3048)
			(end -0.120396 0.2794)
			(stroke
				(width 0.1)
				(type default)
			)
			(layer "B.Fab")
		)
		(fp_line
			(start -0.120396 0.2794)
			(end 0.12065 0.2794)
			(stroke
				(width 0.1)
				(type default)
			)
			(layer "B.Fab")
		)
		(fp_line
			(start -0.12065 -0.2794)
			(end -0.12065 -0.3048)
			(stroke
				(width 0.1)
				(type default)
			)
			(layer "B.Fab")
		)
		(fp_line
			(start -0.12065 -0.3048)
			(end -0.67945 -0.3048)
			(stroke
				(width 0.1)
				(type default)
			)
			(layer "B.Fab")
		)
		(fp_line
			(start -0.67945 0.3048)
			(end -0.120396 0.3048)
			(stroke
				(width 0.1)
				(type default)
			)
			(layer "B.Fab")
		)
		(fp_line
			(start -0.67945 -0.3048)
			(end -0.67945 0.3048)
			(stroke
				(width 0.1)
				(type default)
			)
			(layer "B.Fab")
		)
		(pad "1" smd circle
			(at 0.40005 0)
			(size 0 0)
			(layers "B.Cu" "B.Mask" "B.Paste")
			(net "P12V_HSC_SENSE2_P")
		)
		(pad "2" smd circle
			(at -0.40005 0)
			(size 0 0)
			(layers "B.Cu" "B.Mask" "B.Paste")
			(net "P12V_HSC_SENSE2_R2_P")
		)
	)
	(footprint ""
		(layer "B.Cu")
		(at 119.587772 -284.796738 -90)
		(property "Reference" "PC93"
			(at 0 0 90)
			(layer "B.SilkS")
			(hide yes)
			(effects
				(font
					(size 1.27 1.27)
				)
				(justify mirror)
			)
		)
		(property "Value" ""
			(at 0 0 90)
			(layer "B.Fab")
			(effects
				(font
					(size 1.27 1.27)
				)
				(justify mirror)
			)
		)
		(duplicate_pad_numbers_are_jumpers no)
		(fp_line
			(start -1.524 0.762)
			(end 1.524 0.762)
			(stroke
				(width 0.1524)
				(type default)
			)
			(layer "B.SilkS")
		)
		(fp_line
			(start 1.524 0.762)
			(end 1.524 -0.762)
			(stroke
				(width 0.1524)
				(type default)
			)
			(layer "B.SilkS")
		)
		(fp_line
			(start -1.524 -0.762)
			(end -1.524 0.762)
			(stroke
				(width 0.1524)
				(type default)
			)
			(layer "B.SilkS")
		)
		(fp_line
			(start 1.524 -0.762)
			(end -1.524 -0.762)
			(stroke
				(width 0.1524)
				(type default)
			)
			(layer "B.SilkS")
		)
		(fp_line
			(start -1.1049 0.724916)
			(end -1.1049 -0.724916)
			(stroke
				(width 0.1)
				(type default)
			)
			(layer "B.Fab")
		)
		(fp_line
			(start 1.1049 0.724916)
			(end -1.1049 0.724916)
			(stroke
				(width 0.1)
				(type default)
			)
			(layer "B.Fab")
		)
		(fp_line
			(start -1.1049 -0.724916)
			(end 1.1049 -0.724916)
			(stroke
				(width 0.1)
				(type default)
			)
			(layer "B.Fab")
		)
		(fp_line
			(start 1.1049 -0.724916)
			(end 1.1049 0.724916)
			(stroke
				(width 0.1)
				(type default)
			)
			(layer "B.Fab")
		)
		(pad "1" smd rect
			(at 0.889 0 270)
			(size 1.016 1.27)
			(layers "B.Cu" "B.Mask" "B.Paste")
			(net "SW_P12V_P0V8_PEX1_FLT")
		)
		(pad "2" smd rect
			(at -0.889 0 270)
			(size 1.016 1.27)
			(layers "B.Cu" "B.Mask" "B.Paste")
			(net "GND")
		)
	)
	(footprint ""
		(layer "B.Cu")
		(at 128.59385 -308.668674 90)
		(property "Reference" "C4264"
			(at 0 0 90)
			(layer "B.SilkS")
			(hide yes)
			(effects
				(font
					(size 1.27 1.27)
				)
				(justify mirror)
			)
		)
		(property "Value" ""
			(at 0 0 90)
			(layer "B.Fab")
			(effects
				(font
					(size 1.27 1.27)
				)
				(justify mirror)
			)
		)
		(duplicate_pad_numbers_are_jumpers no)
		(fp_line
			(start 0.299974 -0.150114)
			(end -0.299974 -0.150114)
			(stroke
				(width 0.1)
				(type default)
			)
			(layer "B.Fab")
		)
		(fp_line
			(start -0.299974 -0.150114)
			(end -0.299974 0.150114)
			(stroke
				(width 0.1)
				(type default)
			)
			(layer "B.Fab")
		)
		(fp_line
			(start 0.299974 0.150114)
			(end 0.299974 -0.150114)
			(stroke
				(width 0.1)
				(type default)
			)
			(layer "B.Fab")
		)
		(fp_line
			(start -0.299974 0.150114)
			(end 0.299974 0.150114)
			(stroke
				(width 0.1)
				(type default)
			)
			(layer "B.Fab")
		)
		(pad "1" smd rect
			(at 0.2667 0 270)
			(size 0.3048 0.381)
			(layers "B.Cu" "B.Mask" "B.Paste")
			(net "P0V8_PEX1")
		)
		(pad "2" smd rect
			(at -0.2667 0 270)
			(size 0.3048 0.381)
			(layers "B.Cu" "B.Mask" "B.Paste")
			(net "GND")
		)
	)
	(footprint ""
		(layer "B.Cu")
		(at 52.049934 -299.699934 -90)
		(property "Reference" "C1182"
			(at 0 0 90)
			(layer "B.SilkS")
			(hide yes)
			(effects
				(font
					(size 1.27 1.27)
				)
				(justify mirror)
			)
		)
		(property "Value" ""
			(at 0 0 90)
			(layer "B.Fab")
			(effects
				(font
					(size 1.27 1.27)
				)
				(justify mirror)
			)
		)
		(duplicate_pad_numbers_are_jumpers no)
		(fp_line
			(start -0.299974 0.150114)
			(end 0.299974 0.150114)
			(stroke
				(width 0.1)
				(type default)
			)
			(layer "B.Fab")
		)
		(fp_line
			(start 0.299974 0.150114)
			(end 0.299974 -0.150114)
			(stroke
				(width 0.1)
				(type default)
			)
			(layer "B.Fab")
		)
		(fp_line
			(start -0.299974 -0.150114)
			(end -0.299974 0.150114)
			(stroke
				(width 0.1)
				(type default)
			)
			(layer "B.Fab")
		)
		(fp_line
			(start 0.299974 -0.150114)
			(end -0.299974 -0.150114)
			(stroke
				(width 0.1)
				(type default)
			)
			(layer "B.Fab")
		)
		(pad "1" smd rect
			(at 0.2667 0 90)
			(size 0.3048 0.381)
			(layers "B.Cu" "B.Mask" "B.Paste")
			(net "P0V8_SERDES_VDDA_PEX0")
		)
		(pad "2" smd rect
			(at -0.2667 0 90)
			(size 0.3048 0.381)
			(layers "B.Cu" "B.Mask" "B.Paste")
			(net "GND")
		)
	)
)
